(kicad_pcb
	(version 20260206)
	(generator "pcbnew")
	(generator_version "10.0")
	(general
		(thickness 1.6)
		(legacy_teardrops no)
	)
	(paper "A4")
	(title_block
		(title "Bryce Canyon_IOM_M2_16342-2_OCP.brd")
		(comment 1 "Bryce Canyon / footprints 651-654 of 1146")
	)
	(layers
		(0 "F.Cu" signal "TOP")
		(4 "In1.Cu" signal "L2GND")
		(6 "In2.Cu" signal "L3")
		(8 "In3.Cu" signal "L4VCC")
		(10 "In4.Cu" signal "L5VCC")
		(12 "In5.Cu" signal "L6")
		(14 "In6.Cu" signal "L7GND")
		(2 "B.Cu" signal "BOTTOM")
		(9 "F.Adhes" user "F.Adhesive")
		(11 "B.Adhes" user "B.Adhesive")
		(13 "F.Paste" user "Package Geometry/Pastemask Top")
		(15 "B.Paste" user "Package Geometry/Pastemask Bottom")
		(5 "F.SilkS" user "Ref Des/Silkscreen Top")
		(7 "B.SilkS" user "Ref Des/Silkscreen Bottom")
		(1 "F.Mask" user "Board Geometry/Soldermask Top")
		(3 "B.Mask" user "Board Geometry/Soldermask Bottom")
		(17 "Dwgs.User" user "User.Drawings")
		(19 "Cmts.User" user "User.Comments")
		(21 "Eco1.User" user "User.Eco1")
		(23 "Eco2.User" user "User.Eco2")
		(25 "Edge.Cuts" user "Board Geometry/Outline")
		(27 "Margin" user)
		(31 "F.CrtYd" user "Package Geometry/Place Bound Top")
		(29 "B.CrtYd" user "Package Geometry/Place Bound Bottom")
		(35 "F.Fab" user "Ref Des/Assembly Top")
		(33 "B.Fab" user "Ref Des/Assembly Bottom")
	)
	(footprint ""
		(layer "F.Cu")
		(at 63.119 -165.735 90)
		(property "Reference" "Q3"
			(at 0 0 90)
			(layer "F.SilkS")
			(hide yes)
			(effects
				(font
					(size 1.27 1.27)
				)
			)
		)
		(property "Value" "MMBT3904-3-GP"
			(at 0.10287 -10.29843 90)
			(unlocked yes)
			(layer "F.Fab")
			(hide yes)
			(effects
				(font
					(size 1.016 1.016)
					(thickness 0.1524)
				)
			)
		)
		(property "Device Type" "SOT23CBE2D4H44"
			(at 0.10287 -12.20343 90)
			(unlocked yes)
			(layer "F.Fab")
			(hide yes)
			(effects
				(font
					(size 1.016 1.016)
					(thickness 0.1524)
				)
			)
		)
		(duplicate_pad_numbers_are_jumpers no)
		(fp_line
			(start 1.651 -1.778)
			(end -1.651 -1.778)
			(stroke
				(width 0.1524)
				(type default)
			)
			(layer "F.SilkS")
		)
		(fp_line
			(start -1.651 -1.778)
			(end -1.651 1.778)
			(stroke
				(width 0.1524)
				(type default)
			)
			(layer "F.SilkS")
		)
		(fp_line
			(start 1.651 1.778)
			(end 1.651 -1.778)
			(stroke
				(width 0.1524)
				(type default)
			)
			(layer "F.SilkS")
		)
		(fp_line
			(start -1.651 1.778)
			(end 1.651 1.778)
			(stroke
				(width 0.1524)
				(type default)
			)
			(layer "F.SilkS")
		)
		(fp_poly
			(pts
				(xy -1.778 1.8796) (xy -1.778 -1.8796) (xy 1.778 -1.8796) (xy 1.778 1.8796)
			)
			(stroke
				(width 0)
				(type default)
			)
			(fill no)
			(layer "F.CrtYd")
		)
		(fp_poly
			(pts
				(xy -1.778 1.8796) (xy -1.778 -1.8796) (xy 1.778 -1.8796) (xy 1.778 1.8796)
			)
			(stroke
				(width 0)
				(type default)
			)
			(fill no)
			(layer "F.Fab")
		)
		(pad "B" smd custom
			(at -0.98425 0.9525 90)
			(size 0.1905 0.1905)
			(layers "F.Cu" "F.Mask" "F.Paste")
			(net "FM_TPM_PRSNT_RST_N_R")
			(options
				(clearance outline)
				(anchor circle)
			)
			(primitives
				(gr_poly
					(pts
						(arc
							(start -0.1778 0.5715)
							(mid -0.321484 0.511984)
							(end -0.381 0.3683)
						)
						(arc
							(start -0.381 -0.3683)
							(mid -0.321484 -0.511984)
							(end -0.1778 -0.5715)
						)
						(arc
							(start 0.1778 -0.5715)
							(mid 0.321484 -0.511984)
							(end 0.381 -0.3683)
						)
						(arc
							(start 0.381 0.3683)
							(mid 0.321484 0.511984)
							(end 0.1778 0.5715)
						)
					)
					(width 0)
					(fill yes)
				)
			)
		)
		(pad "C" smd custom
			(at 0 -0.9525 90)
			(size 0.1905 0.1905)
			(layers "F.Cu" "F.Mask" "F.Paste")
			(net "FM_TPM_PRSNT_RST")
			(options
				(clearance outline)
				(anchor circle)
			)
			(primitives
				(gr_poly
					(pts
						(arc
							(start -0.1778 0.5715)
							(mid -0.321484 0.511984)
							(end -0.381 0.3683)
						)
						(arc
							(start -0.381 -0.3683)
							(mid -0.321484 -0.511984)
							(end -0.1778 -0.5715)
						)
						(arc
							(start 0.1778 -0.5715)
							(mid 0.321484 -0.511984)
							(end 0.381 -0.3683)
						)
						(arc
							(start 0.381 0.3683)
							(mid 0.321484 0.511984)
							(end 0.1778 0.5715)
						)
					)
					(width 0)
					(fill yes)
				)
			)
		)
		(pad "E" smd custom
			(at 0.98425 0.9525 90)
			(size 0.1905 0.1905)
			(layers "F.Cu" "F.Mask" "F.Paste")
			(net "GND")
			(options
				(clearance outline)
				(anchor circle)
			)
			(primitives
				(gr_poly
					(pts
						(arc
							(start -0.1778 0.5715)
							(mid -0.321484 0.511984)
							(end -0.381 0.3683)
						)
						(arc
							(start -0.381 -0.3683)
							(mid -0.321484 -0.511984)
							(end -0.1778 -0.5715)
						)
						(arc
							(start 0.1778 -0.5715)
							(mid 0.321484 -0.511984)
							(end 0.381 -0.3683)
						)
						(arc
							(start 0.381 0.3683)
							(mid 0.321484 0.511984)
							(end 0.1778 0.5715)
						)
					)
					(width 0)
					(fill yes)
				)
			)
		)
	)
	(footprint ""
		(layer "F.Cu")
		(at 118.872 -8.9916 90)
		(property "Reference" "U35"
			(at 0 0 90)
			(layer "F.SilkS")
			(hide yes)
			(effects
				(font
					(size 1.27 1.27)
				)
			)
		)
		(property "Value" "ADM1278-2ACPZ-RL-1-GP"
			(at -4.7625 -7.4422 90)
			(unlocked yes)
			(layer "F.Fab")
			(hide yes)
			(effects
				(font
					(size 1.016 1.016)
					(thickness 0.1524)
				)
			)
		)
		(property "Device Type" "QFN32-G3D45-UH32"
			(at -4.7625 -8.9662 90)
			(unlocked yes)
			(layer "F.Fab")
			(hide yes)
			(effects
				(font
					(size 1.016 1.016)
					(thickness 0.1524)
				)
			)
		)
		(duplicate_pad_numbers_are_jumpers no)
		(fp_line
			(start -0.250698 -3.7973)
			(end -0.250698 -3.2893)
			(stroke
				(width 0.1524)
				(type default)
			)
			(layer "F.SilkS")
		)
		(fp_line
			(start -3.5179 -3.5179)
			(end -2.2479 -3.5179)
			(stroke
				(width 0.1524)
				(type default)
			)
			(layer "F.SilkS")
		)
		(fp_line
			(start -3.5179 -2.2479)
			(end -3.5179 -3.5179)
			(stroke
				(width 0.1524)
				(type default)
			)
			(layer "F.SilkS")
		)
		(fp_line
			(start -4.0513 -1.24968)
			(end -3.2893 -1.24968)
			(stroke
				(width 0.1524)
				(type default)
			)
			(layer "F.SilkS")
		)
		(fp_line
			(start 4.0513 -0.749808)
			(end 3.2893 -0.749808)
			(stroke
				(width 0.1524)
				(type default)
			)
			(layer "F.SilkS")
		)
		(fp_line
			(start -3.7973 1.24968)
			(end -3.2893 1.24968)
			(stroke
				(width 0.1524)
				(type default)
			)
			(layer "F.SilkS")
		)
		(fp_line
			(start 3.7973 1.749552)
			(end 3.2893 1.749552)
			(stroke
				(width 0.1524)
				(type default)
			)
			(layer "F.SilkS")
		)
		(fp_line
			(start 3.5179 2.2479)
			(end 3.5179 3.5179)
			(stroke
				(width 0.1524)
				(type default)
			)
			(layer "F.SilkS")
		)
		(fp_line
			(start -3.5179 2.2479)
			(end -3.5179 3.5179)
			(stroke
				(width 0.1524)
				(type default)
			)
			(layer "F.SilkS")
		)
		(fp_line
			(start 3.5179 3.5179)
			(end 2.2479 3.5179)
			(stroke
				(width 0.1524)
				(type default)
			)
			(layer "F.SilkS")
		)
		(fp_line
			(start -3.5179 3.5179)
			(end -2.2479 3.5179)
			(stroke
				(width 0.1524)
				(type default)
			)
			(layer "F.SilkS")
		)
		(fp_line
			(start -0.250698 4.0513)
			(end -0.250698 3.2893)
			(stroke
				(width 0.1524)
				(type default)
			)
			(layer "F.SilkS")
		)
		(fp_poly
			(pts
				(xy 2.2479 -3.5179) (xy 3.5179 -2.2479) (xy 3.5179 -3.5179)
			)
			(stroke
				(width 0)
				(type default)
			)
			(fill yes)
			(layer "F.SilkS")
		)
		(fp_rect
			(start -2.5019 2.5019)
			(end 2.5019 -2.5019)
			(stroke
				(width 0)
				(type default)
			)
			(fill no)
			(layer "F.CrtYd")
		)
		(fp_poly
			(pts
				(xy -3.5179 3.5179) (xy -3.5179 -3.5179) (xy 3.5179 -3.5179) (xy 3.5179 3.5179) (xy -2.49682 3.5179)
				(xy -2.49682 2.5019) (xy 2.5019 2.5019) (xy 2.5019 -2.5019) (xy -2.5019 -2.5019) (xy -2.5019 3.5179)
			)
			(stroke
				(width 0)
				(type default)
			)
			(fill no)
			(layer "F.CrtYd")
		)
		(fp_rect
			(start -3.5179 3.5179)
			(end 3.5179 -3.5179)
			(stroke
				(width 0)
				(type default)
			)
			(fill no)
			(layer "F.Fab")
		)
		(pad "1" smd rect
			(at 1.75006 -2.5527 90)
			(size 0.3048 0.9144)
			(layers "F.Cu" "F.Mask" "F.Paste")
			(net "MB0_PSET_R")
		)
		(pad "2" smd rect
			(at 1.249934 -2.4765 90)
			(size 0.3048 1.0668)
			(layers "F.Cu" "F.Mask" "F.Paste")
			(net "MB0_VCAP_R")
		)
		(pad "3" smd rect
			(at 0.750062 -2.4765 90)
			(size 0.3048 1.0668)
			(layers "F.Cu" "F.Mask" "F.Paste")
			(net "MB0_ISET_R")
		)
		(pad "4" smd rect
			(at 0.249936 -2.4765 90)
			(size 0.3048 1.0668)
			(layers "F.Cu" "F.Mask" "F.Paste")
			(net "MB0_ISTART_R")
		)
		(pad "5" smd rect
			(at -0.249936 -2.4765 90)
			(size 0.3048 1.0668)
			(layers "F.Cu" "F.Mask" "F.Paste")
			(net "MB0_TIME_R")
		)
		(pad "6" smd rect
			(at -0.750062 -2.4765 90)
			(size 0.3048 1.0668)
			(layers "F.Cu" "F.Mask" "F.Paste")
			(net "Net_527")
		)
		(pad "7" smd rect
			(at -1.249934 -2.4765 90)
			(size 0.3048 1.0668)
			(layers "F.Cu" "F.Mask" "F.Paste")
			(net "MB0_CM_ADR1_R")
		)
		(pad "8" smd rect
			(at -1.75006 -2.5527 90)
			(size 0.3048 0.9144)
			(layers "F.Cu" "F.Mask" "F.Paste")
			(net "MB0_CM_ADR2_R")
		)
		(pad "9" smd rect
			(at -2.5527 -1.75006 90)
			(size 0.9144 0.3048)
			(layers "F.Cu" "F.Mask" "F.Paste")
			(net "MB0_SPISS_PD")
		)
		(pad "10" smd rect
			(at -2.4765 -1.249934 90)
			(size 1.0668 0.3048)
			(layers "F.Cu" "F.Mask" "F.Paste")
			(net "Net_531")
		)
		(pad "11" smd rect
			(at -2.4765 -0.750062 90)
			(size 1.0668 0.3048)
			(layers "F.Cu" "F.Mask" "F.Paste")
			(net "Net_530")
		)
		(pad "12" smd rect
			(at -2.4765 -0.249936 90)
			(size 1.0668 0.3048)
			(layers "F.Cu" "F.Mask" "F.Paste")
			(net "MB0_HS_ENABLE")
		)
		(pad "13" smd rect
			(at -2.4765 0.249936 90)
			(size 1.0668 0.3048)
			(layers "F.Cu" "F.Mask" "F.Paste")
			(net "Net_529")
		)
		(pad "14" smd rect
			(at -2.4765 0.750062 90)
			(size 1.0668 0.3048)
			(layers "F.Cu" "F.Mask" "F.Paste")
			(net "Net_528")
		)
		(pad "15" smd rect
			(at -2.4765 1.249934 90)
			(size 1.0668 0.3048)
			(layers "F.Cu" "F.Mask" "F.Paste")
			(net "HSW_SDA")
		)
		(pad "16" smd rect
			(at -2.5527 1.75006 90)
			(size 0.9144 0.3048)
			(layers "F.Cu" "F.Mask" "F.Paste")
			(net "HSW_SCL")
		)
		(pad "17" smd rect
			(at -1.75006 2.5527 90)
			(size 0.3048 0.9144)
			(layers "F.Cu" "F.Mask" "F.Paste")
			(net "MB0_RETRY_R")
		)
		(pad "18" smd rect
			(at -1.249934 2.4765 90)
			(size 0.3048 1.0668)
			(layers "F.Cu" "F.Mask" "F.Paste")
			(net "P12V_IOM_PGOOD")
		)
		(pad "19" smd rect
			(at -0.750062 2.4765 90)
			(size 0.3048 1.0668)
			(layers "F.Cu" "F.Mask" "F.Paste")
			(net "Net_532")
		)
		(pad "20" smd rect
			(at -0.249936 2.4765 90)
			(size 0.3048 1.0668)
			(layers "F.Cu" "F.Mask" "F.Paste")
			(net "MB0_CM_VOUT_R")
		)
		(pad "21" smd rect
			(at 0.249936 2.4765 90)
			(size 0.3048 1.0668)
			(layers "F.Cu" "F.Mask" "F.Paste")
			(net "MB0_P12V_PWGIN_R")
		)
		(pad "22" smd rect
			(at 0.750062 2.4765 90)
			(size 0.3048 1.0668)
			(layers "F.Cu" "F.Mask" "F.Paste")
			(net "AGND_CURRENT_MON")
		)
		(pad "23" smd rect
			(at 1.249934 2.4765 90)
			(size 0.3048 1.0668)
			(layers "F.Cu" "F.Mask" "F.Paste")
			(net "GND")
		)
		(pad "24" smd rect
			(at 1.75006 2.5527 90)
			(size 0.3048 0.9144)
			(layers "F.Cu" "F.Mask" "F.Paste")
			(net "MB0_CM_GATE")
		)
		(pad "25" smd rect
			(at 2.5527 1.75006 90)
			(size 0.9144 0.3048)
			(layers "F.Cu" "F.Mask" "F.Paste")
			(net "MB0_TEMP")
		)
		(pad "26" smd rect
			(at 2.4765 1.249934 90)
			(size 1.0668 0.3048)
			(layers "F.Cu" "F.Mask" "F.Paste")
			(net "MB0_CM_SENSE_N")
		)
		(pad "27" smd rect
			(at 2.4765 0.750062 90)
			(size 1.0668 0.3048)
			(layers "F.Cu" "F.Mask" "F.Paste")
			(net "ADM1278_HS_N")
		)
		(pad "28" smd rect
			(at 2.4765 0.249936 90)
			(size 1.0668 0.3048)
			(layers "F.Cu" "F.Mask" "F.Paste")
			(net "ADM1278_HS_P")
		)
		(pad "29" smd rect
			(at 2.4765 -0.249936 90)
			(size 1.0668 0.3048)
			(layers "F.Cu" "F.Mask" "F.Paste")
			(net "MB0_CM_SENSE_P")
		)
		(pad "30" smd rect
			(at 2.4765 -0.750062 90)
			(size 1.0668 0.3048)
			(layers "F.Cu" "F.Mask" "F.Paste")
			(net "MB0_VCC")
		)
		(pad "31" smd rect
			(at 2.4765 -1.249934 90)
			(size 1.0668 0.3048)
			(layers "F.Cu" "F.Mask" "F.Paste")
			(net "MB0_CM_UV_R")
		)
		(pad "32" smd rect
			(at 2.5527 -1.75006 90)
			(size 0.9144 0.3048)
			(layers "F.Cu" "F.Mask" "F.Paste")
			(net "MB0_CM_OV_R")
		)
		(pad "33" smd rect
			(at 0 0 90)
			(size 3.4544 3.4544)
			(layers "F.Cu" "F.Mask" "F.Paste")
			(net "AGND_CURRENT_MON")
		)
	)
	(footprint ""
		(layer "F.Cu")
		(at 156.475938 -16.029178 90)
		(property "Reference" "C203"
			(at 0 0 90)
			(layer "F.SilkS")
			(hide yes)
			(effects
				(font
					(size 1.27 1.27)
				)
			)
		)
		(property "Value" "SCD1U16V2KX-3GP"
			(at 1.1811 -2.7051 90)
			(unlocked yes)
			(layer "F.Fab")
			(hide yes)
			(effects
				(font
					(size 1.016 1.016)
					(thickness 0.1524)
				)
			)
		)
		(property "Device Type" "C402H22"
			(at 1.1811 -4.2291 90)
			(unlocked yes)
			(layer "F.Fab")
			(hide yes)
			(effects
				(font
					(size 1.016 1.016)
					(thickness 0.1524)
				)
			)
		)
		(duplicate_pad_numbers_are_jumpers no)
		(fp_rect
			(start -0.4318 0.9525)
			(end 0.4318 -0.9525)
			(stroke
				(width 0)
				(type default)
			)
			(fill no)
			(layer "F.CrtYd")
		)
		(fp_rect
			(start -0.4318 0.9525)
			(end 0.4318 -0.9525)
			(stroke
				(width 0)
				(type default)
			)
			(fill no)
			(layer "F.Fab")
		)
		(pad "1" smd custom
			(at 0 -0.4445 90)
			(size 0.1524 0.1524)
			(layers "F.Cu" "F.Mask" "F.Paste")
			(net "P12V_STBY_VIN_PU4")
			(options
				(clearance outline)
				(anchor circle)
			)
			(primitives
				(gr_poly
					(pts
						(arc
							(start 0.3048 -0.2032)
							(mid 0.275042 -0.275042)
							(end 0.2032 -0.3048)
						)
						(arc
							(start -0.2032 -0.3048)
							(mid -0.275042 -0.275042)
							(end -0.3048 -0.2032)
						)
						(arc
							(start -0.3048 0.2032)
							(mid -0.275042 0.275042)
							(end -0.2032 0.3048)
						)
						(arc
							(start 0.2032 0.3048)
							(mid 0.275042 0.275042)
							(end 0.3048 0.2032)
						)
					)
					(width 0)
					(fill yes)
				)
			)
		)
		(pad "2" smd custom
			(at 0 0.4445 90)
			(size 0.1524 0.1524)
			(layers "F.Cu" "F.Mask" "F.Paste")
			(net "GND")
			(options
				(clearance outline)
				(anchor circle)
			)
			(primitives
				(gr_poly
					(pts
						(arc
							(start 0.3048 -0.2032)
							(mid 0.275042 -0.275042)
							(end 0.2032 -0.3048)
						)
						(arc
							(start -0.2032 -0.3048)
							(mid -0.275042 -0.275042)
							(end -0.3048 -0.2032)
						)
						(arc
							(start -0.3048 0.2032)
							(mid -0.275042 0.275042)
							(end -0.2032 0.3048)
						)
						(arc
							(start 0.2032 0.3048)
							(mid 0.275042 0.275042)
							(end 0.3048 0.2032)
						)
					)
					(width 0)
					(fill yes)
				)
			)
		)
	)
	(footprint ""
		(layer "F.Cu")
		(at 47.380398 -131.490974 180)
		(property "Reference" "R265"
			(at 0 0 180)
			(layer "F.SilkS")
			(hide yes)
			(effects
				(font
					(size 1.27 1.27)
				)
			)
		)
		(property "Value" "4K7R2F-GP"
			(at 0.064008 -3.993896 180)
			(unlocked yes)
			(layer "F.Fab")
			(hide yes)
			(effects
				(font
					(size 1.016 1.016)
					(thickness 0.1524)
				)
			)
		)
		(property "Device Type" "R402H16"
			(at 0.064008 -5.517896 180)
			(unlocked yes)
			(layer "F.Fab")
			(hide yes)
			(effects
				(font
					(size 1.016 1.016)
					(thickness 0.1524)
				)
			)
		)
		(duplicate_pad_numbers_are_jumpers no)
		(fp_line
			(start 0.508 -0.9398)
			(end -0.508 -0.9398)
			(stroke
				(width 0.1524)
				(type default)
			)
			(layer "F.SilkS")
		)
		(fp_line
			(start -0.508 -0.9398)
			(end -0.508 0.9398)
			(stroke
				(width 0.1524)
				(type default)
			)
			(layer "F.SilkS")
		)
		(fp_rect
			(start -0.508 0.9398)
			(end 0.508 -0.9398)
			(stroke
				(width 0)
				(type default)
			)
			(fill no)
			(layer "F.CrtYd")
		)
		(fp_rect
			(start -0.508 0.9398)
			(end 0.508 -0.9398)
			(stroke
				(width 0)
				(type default)
			)
			(fill no)
			(layer "F.Fab")
		)
		(pad "1" smd custom
			(at 0 -0.4445 180)
			(size 0.1397 0.1397)
			(layers "F.Cu" "F.Mask" "F.Paste")
			(net "P3V3_STBY")
			(options
				(clearance outline)
				(anchor circle)
			)
			(primitives
				(gr_poly
					(pts
						(arc
							(start -0.1778 -0.2794)
							(mid -0.249642 -0.249642)
							(end -0.2794 -0.1778)
						)
						(arc
							(start -0.2794 0.1778)
							(mid -0.249642 0.249642)
							(end -0.1778 0.2794)
						)
						(arc
							(start 0.1778 0.2794)
							(mid 0.249642 0.249642)
							(end 0.2794 0.1778)
						)
						(arc
							(start 0.2794 -0.1778)
							(mid 0.249642 -0.249642)
							(end 0.1778 -0.2794)
						)
					)
					(width 0)
					(fill yes)
				)
			)
		)
		(pad "2" smd custom
			(at 0 0.4445 180)
			(size 0.1397 0.1397)
			(layers "F.Cu" "F.Mask" "F.Paste")
			(net "BMC_GPIOY3")
			(options
				(clearance outline)
				(anchor circle)
			)
			(primitives
				(gr_poly
					(pts
						(arc
							(start -0.1778 -0.2794)
							(mid -0.249642 -0.249642)
							(end -0.2794 -0.1778)
						)
						(arc
							(start -0.2794 0.1778)
							(mid -0.249642 0.249642)
							(end -0.1778 0.2794)
						)
						(arc
							(start 0.1778 0.2794)
							(mid 0.249642 0.249642)
							(end 0.2794 0.1778)
						)
						(arc
							(start 0.2794 -0.1778)
							(mid 0.249642 -0.249642)
							(end 0.1778 -0.2794)
						)
					)
					(width 0)
					(fill yes)
				)
			)
		)
	)
)
